# T6G (Grand Teton) — schematic netlist excerpt (pin names and nets, part order shuffled) for the footprints in the layout excerpt that follows; sources: Cadence DE-HDL packaged netlist, KiCad conversion of 04192023_DAF0TMB3IC0_F0TG_MB_C_brd_V02_OCP.brd

R3725  Q_RES  2.2K 5% CHIP  pkg 0402LF  page 252 : A = P3V3_AUX ; B = SMB_LM75_0_3V3AUX_SCL
R8007  Q_RES  33 5% CHIP  pkg 0402LF  page 77 : A = SPI_CPU0_D0 ; B = SPI_CPU0_R1_D0
C6694  Q_CAP_DIFFBUS  DIFF BUS_0.22UF 6.3V 20% X6S  pkg C0201  page 341 : \1\ = P5E_CPU1_P2_TX_BUF_C_DN<0> ; \2\ = P5E_CPU1_P2_TX_BUF_DN<0>

(kicad_pcb
	(version 20260206)
	(generator "pcbnew")
	(generator_version "10.0")
	(general
		(thickness 1.6)
		(legacy_teardrops no)
	)
	(paper "A4")
	(title_block
		(title "04192023_DAF0TMB3IC0_F0TG_MB_C_brd_V02_OCP.brd")
		(comment 1 "Grand Teton / footprints 1060-1062 of 8354")
	)
	(layers
		(0 "F.Cu" signal "TOP")
		(4 "In1.Cu" signal "GND")
		(6 "In2.Cu" signal "IN1")
		(8 "In3.Cu" signal "GND1")
		(10 "In4.Cu" signal "IN2")
		(12 "In5.Cu" signal "GND2")
		(14 "In6.Cu" signal "IN3")
		(16 "In7.Cu" signal "GND3")
		(18 "In8.Cu" signal "VCC")
		(20 "In9.Cu" signal "VCC1")
		(22 "In10.Cu" signal "GND4")
		(24 "In11.Cu" signal "IN4")
		(26 "In12.Cu" signal "GND5")
		(28 "In13.Cu" signal "IN5")
		(30 "In14.Cu" signal "GND6")
		(32 "In15.Cu" signal "IN6")
		(34 "In16.Cu" signal "GND7")
		(2 "B.Cu" signal "BOTTOM")
		(9 "F.Adhes" user "F.Adhesive")
		(11 "B.Adhes" user "B.Adhesive")
		(13 "F.Paste" user "Package Geometry/Pastemask Top")
		(15 "B.Paste" user "Package Geometry/Pastemask Bottom")
		(5 "F.SilkS" user "Ref Des/Silkscreen Top")
		(7 "B.SilkS" user "Ref Des/Silkscreen Bottom")
		(1 "F.Mask" user "Board Geometry/Soldermask Top")
		(3 "B.Mask" user "Board Geometry/Soldermask Bottom")
		(17 "Dwgs.User" user "User.Drawings")
		(19 "Cmts.User" user "User.Comments")
		(21 "Eco1.User" user "User.Eco1")
		(23 "Eco2.User" user "User.Eco2")
		(25 "Edge.Cuts" user "Board Geometry/Outline")
		(27 "Margin" user)
		(31 "F.CrtYd" user "Package Geometry/Place Bound Top")
		(29 "B.CrtYd" user "Package Geometry/Place Bound Bottom")
		(35 "F.Fab" user "Ref Des/Assembly Top")
		(33 "B.Fab" user "Ref Des/Assembly Bottom")
	)
	(footprint ""
		(layer "F.Cu")
		(at 263.017 -141.986 -90)
		(property "Reference" "R8007"
			(at 0 0 270)
			(layer "F.SilkS")
			(hide yes)
			(effects
				(font
					(size 1.27 1.27)
				)
			)
		)
		(property "Value" ""
			(at 0 0 270)
			(layer "F.Fab")
			(effects
				(font
					(size 1.27 1.27)
				)
			)
		)
		(duplicate_pad_numbers_are_jumpers no)
		(fp_line
			(start -0.7874 0.4064)
			(end -0.7874 -0.4064)
			(stroke
				(width 0.1524)
				(type default)
			)
			(layer "F.SilkS")
		)
		(fp_line
			(start 0.7874 0.4064)
			(end -0.7874 0.4064)
			(stroke
				(width 0.1524)
				(type default)
			)
			(layer "F.SilkS")
		)
		(fp_line
			(start -0.7874 -0.4064)
			(end 0.7874 -0.4064)
			(stroke
				(width 0.1524)
				(type default)
			)
			(layer "F.SilkS")
		)
		(fp_line
			(start 0.7874 -0.4064)
			(end 0.7874 0.4064)
			(stroke
				(width 0.1524)
				(type default)
			)
			(layer "F.SilkS")
		)
		(fp_line
			(start -0.67945 0.3048)
			(end -0.67945 -0.305054)
			(stroke
				(width 0.1)
				(type default)
			)
			(layer "F.Fab")
		)
		(fp_line
			(start -0.12065 0.3048)
			(end -0.67945 0.3048)
			(stroke
				(width 0.1)
				(type default)
			)
			(layer "F.Fab")
		)
		(fp_line
			(start 0.120396 0.3048)
			(end 0.120396 0.2794)
			(stroke
				(width 0.1)
				(type default)
			)
			(layer "F.Fab")
		)
		(fp_line
			(start 0.67945 0.3048)
			(end 0.120396 0.3048)
			(stroke
				(width 0.1)
				(type default)
			)
			(layer "F.Fab")
		)
		(fp_line
			(start -0.12065 0.2794)
			(end -0.12065 0.3048)
			(stroke
				(width 0.1)
				(type default)
			)
			(layer "F.Fab")
		)
		(fp_line
			(start 0.120396 0.2794)
			(end -0.12065 0.2794)
			(stroke
				(width 0.1)
				(type default)
			)
			(layer "F.Fab")
		)
		(fp_line
			(start -0.12065 -0.2794)
			(end 0.12065 -0.2794)
			(stroke
				(width 0.1)
				(type default)
			)
			(layer "F.Fab")
		)
		(fp_line
			(start 0.12065 -0.2794)
			(end 0.12065 -0.3048)
			(stroke
				(width 0.1)
				(type default)
			)
			(layer "F.Fab")
		)
		(fp_line
			(start 0.12065 -0.3048)
			(end 0.67945 -0.3048)
			(stroke
				(width 0.1)
				(type default)
			)
			(layer "F.Fab")
		)
		(fp_line
			(start 0.67945 -0.3048)
			(end 0.67945 0.3048)
			(stroke
				(width 0.1)
				(type default)
			)
			(layer "F.Fab")
		)
		(fp_line
			(start -0.67945 -0.305054)
			(end -0.12065 -0.305054)
			(stroke
				(width 0.1)
				(type default)
			)
			(layer "F.Fab")
		)
		(fp_line
			(start -0.12065 -0.305054)
			(end -0.12065 -0.2794)
			(stroke
				(width 0.1)
				(type default)
			)
			(layer "F.Fab")
		)
		(pad "1" smd circle
			(at -0.40005 0 270)
			(size 0 0)
			(layers "F.Cu" "F.Mask" "F.Paste")
			(net "SPI_CPU0_D0")
		)
		(pad "2" smd circle
			(at 0.40005 0 270)
			(size 0 0)
			(layers "F.Cu" "F.Mask" "F.Paste")
			(net "SPI_CPU0_R1_D0")
		)
	)
	(footprint ""
		(layer "F.Cu")
		(at 114.868706 -408.517344 -90)
		(property "Reference" "C6694"
			(at 0 0 270)
			(layer "F.SilkS")
			(hide yes)
			(effects
				(font
					(size 1.27 1.27)
				)
			)
		)
		(property "Value" ""
			(at 0 0 270)
			(layer "F.Fab")
			(effects
				(font
					(size 1.27 1.27)
				)
			)
		)
		(duplicate_pad_numbers_are_jumpers no)
		(fp_line
			(start -0.299974 0.150114)
			(end -0.299974 -0.150114)
			(stroke
				(width 0.1)
				(type default)
			)
			(layer "F.Fab")
		)
		(fp_line
			(start 0.299974 0.150114)
			(end -0.299974 0.150114)
			(stroke
				(width 0.1)
				(type default)
			)
			(layer "F.Fab")
		)
		(fp_line
			(start -0.299974 -0.150114)
			(end 0.299974 -0.150114)
			(stroke
				(width 0.1)
				(type default)
			)
			(layer "F.Fab")
		)
		(fp_line
			(start 0.299974 -0.150114)
			(end 0.299974 0.150114)
			(stroke
				(width 0.1)
				(type default)
			)
			(layer "F.Fab")
		)
		(pad "1" smd rect
			(at -0.2667 0 270)
			(size 0.3048 0.381)
			(layers "F.Cu" "F.Mask" "F.Paste")
			(net "P5E_CPU1_P2_TX_BUF_C_DN<0>")
		)
		(pad "2" smd rect
			(at 0.2667 0 270)
			(size 0.3048 0.381)
			(layers "F.Cu" "F.Mask" "F.Paste")
			(net "P5E_CPU1_P2_TX_BUF_DN<0>")
		)
	)
	(footprint ""
		(layer "F.Cu")
		(at 254.592836 -118.91645)
		(property "Reference" "R3725"
			(at 0 0 0)
			(layer "F.SilkS")
			(hide yes)
			(effects
				(font
					(size 1.27 1.27)
				)
			)
		)
		(property "Value" ""
			(at 0 0 0)
			(layer "F.Fab")
			(effects
				(font
					(size 1.27 1.27)
				)
			)
		)
		(duplicate_pad_numbers_are_jumpers no)
		(fp_line
			(start -0.7874 -0.4064)
			(end 0.7874 -0.4064)
			(stroke
				(width 0.1524)
				(type default)
			)
			(layer "F.SilkS")
		)
		(fp_line
			(start -0.7874 0.4064)
			(end -0.7874 -0.4064)
			(stroke
				(width 0.1524)
				(type default)
			)
			(layer "F.SilkS")
		)
		(fp_line
			(start 0.7874 -0.4064)
			(end 0.7874 0.4064)
			(stroke
				(width 0.1524)
				(type default)
			)
			(layer "F.SilkS")
		)
		(fp_line
			(start 0.7874 0.4064)
			(end -0.7874 0.4064)
			(stroke
				(width 0.1524)
				(type default)
			)
			(layer "F.SilkS")
		)
		(fp_line
			(start -0.67945 -0.305054)
			(end -0.12065 -0.305054)
			(stroke
				(width 0.1)
				(type default)
			)
			(layer "F.Fab")
		)
		(fp_line
			(start -0.67945 0.3048)
			(end -0.67945 -0.305054)
			(stroke
				(width 0.1)
				(type default)
			)
			(layer "F.Fab")
		)
		(fp_line
			(start -0.12065 -0.305054)
			(end -0.12065 -0.2794)
			(stroke
				(width 0.1)
				(type default)
			)
			(layer "F.Fab")
		)
		(fp_line
			(start -0.12065 -0.2794)
			(end 0.12065 -0.2794)
			(stroke
				(width 0.1)
				(type default)
			)
			(layer "F.Fab")
		)
		(fp_line
			(start -0.12065 0.2794)
			(end -0.12065 0.3048)
			(stroke
				(width 0.1)
				(type default)
			)
			(layer "F.Fab")
		)
		(fp_line
			(start -0.12065 0.3048)
			(end -0.67945 0.3048)
			(stroke
				(width 0.1)
				(type default)
			)
			(layer "F.Fab")
		)
		(fp_line
			(start 0.120396 0.2794)
			(end -0.12065 0.2794)
			(stroke
				(width 0.1)
				(type default)
			)
			(layer "F.Fab")
		)
		(fp_line
			(start 0.120396 0.3048)
			(end 0.120396 0.2794)
			(stroke
				(width 0.1)
				(type default)
			)
			(layer "F.Fab")
		)
		(fp_line
			(start 0.12065 -0.3048)
			(end 0.67945 -0.3048)
			(stroke
				(width 0.1)
				(type default)
			)
			(layer "F.Fab")
		)
		(fp_line
			(start 0.12065 -0.2794)
			(end 0.12065 -0.3048)
			(stroke
				(width 0.1)
				(type default)
			)
			(layer "F.Fab")
		)
		(fp_line
			(start 0.67945 -0.3048)
			(end 0.67945 0.3048)
			(stroke
				(width 0.1)
				(type default)
			)
			(layer "F.Fab")
		)
		(fp_line
			(start 0.67945 0.3048)
			(end 0.120396 0.3048)
			(stroke
				(width 0.1)
				(type default)
			)
			(layer "F.Fab")
		)
		(pad "1" smd circle
			(at -0.40005 0)
			(size 0 0)
			(layers "F.Cu" "F.Mask" "F.Paste")
			(net "P3V3_AUX")
		)
		(pad "2" smd circle
			(at 0.40005 0)
			(size 0 0)
			(layers "F.Cu" "F.Mask" "F.Paste")
			(net "SMB_LM75_0_3V3AUX_SCL")
		)
	)
)
